(kicad_pcb
	(version 20260206)
	(generator "pcbnew")
	(generator_version "10.0")
	(general
		(thickness 1.6)
		(legacy_teardrops no)
	)
	(paper "A4")
	(title_block
		(title "baseboard — 13948-1b.1110WZS1818.brd")
		(comment 1 "Honey Badger (Wiwynn) / footprints 458-463 of 2523")
	)
	(layers
		(0 "F.Cu" signal "TOP")
		(4 "In1.Cu" signal "L2GND")
		(6 "In2.Cu" signal "L3")
		(8 "In3.Cu" signal "L4VCC")
		(10 "In4.Cu" signal "L5VCC")
		(12 "In5.Cu" signal "L6")
		(14 "In6.Cu" signal "L7GND")
		(2 "B.Cu" signal "BOTTOM")
		(9 "F.Adhes" user "F.Adhesive")
		(11 "B.Adhes" user "B.Adhesive")
		(13 "F.Paste" user "Package Geometry/Pastemask Top")
		(15 "B.Paste" user "Package Geometry/Pastemask Bottom")
		(5 "F.SilkS" user "Ref Des/Silkscreen Top")
		(7 "B.SilkS" user "Ref Des/Silkscreen Bottom")
		(1 "F.Mask" user "Board Geometry/Soldermask Top")
		(3 "B.Mask" user "Board Geometry/Soldermask Bottom")
		(17 "Dwgs.User" user "User.Drawings")
		(19 "Cmts.User" user "User.Comments")
		(21 "Eco1.User" user "User.Eco1")
		(23 "Eco2.User" user "User.Eco2")
		(25 "Edge.Cuts" user "Board Geometry/Outline")
		(27 "Margin" user)
		(31 "F.CrtYd" user "Package Geometry/Place Bound Top")
		(29 "B.CrtYd" user "Package Geometry/Place Bound Bottom")
		(35 "F.Fab" user "Ref Des/Assembly Top")
		(33 "B.Fab" user "Ref Des/Assembly Bottom")
	)
	(footprint ""
		(layer "F.Cu")
		(at 102.37597 -114.3 180)
		(property "Reference" "SC1090"
			(at 0 0 180)
			(layer "F.SilkS")
			(hide yes)
			(effects
				(font
					(size 1.27 1.27)
				)
			)
		)
		(property "Value" "SCD01U10V1KX-GP"
			(at -2.8321 -1.7399 180)
			(unlocked yes)
			(layer "F.Fab")
			(hide yes)
			(effects
				(font
					(size 1.016 1.016)
					(thickness 0.1524)
				)
			)
		)
		(property "Device Type" "C0201H13"
			(at -2.8321 -3.2639 180)
			(unlocked yes)
			(layer "F.Fab")
			(hide yes)
			(effects
				(font
					(size 1.016 1.016)
					(thickness 0.1524)
				)
			)
		)
		(duplicate_pad_numbers_are_jumpers no)
		(fp_rect
			(start -0.2794 0.6477)
			(end 0.2794 -0.6477)
			(stroke
				(width 0)
				(type default)
			)
			(fill no)
			(layer "F.CrtYd")
		)
		(fp_rect
			(start -0.2794 0.6477)
			(end 0.2794 -0.6477)
			(stroke
				(width 0)
				(type default)
			)
			(fill no)
			(layer "F.Fab")
		)
		(pad "1" smd custom
			(at 0 -0.2794 180)
			(size 0.0762 0.0762)
			(layers "F.Cu" "F.Mask" "F.Paste")
			(net "SAS_HDD_TX11_P")
			(options
				(clearance outline)
				(anchor circle)
			)
			(primitives
				(gr_poly
					(pts
						(arc
							(start 0.1524 -0.127)
							(mid 0.137521 -0.162921)
							(end 0.1016 -0.1778)
						)
						(arc
							(start -0.1016 -0.1778)
							(mid -0.137521 -0.162921)
							(end -0.1524 -0.127)
						)
						(arc
							(start -0.1524 0.127)
							(mid -0.137521 0.162921)
							(end -0.1016 0.1778)
						)
						(arc
							(start 0.1016 0.1778)
							(mid 0.137521 0.162921)
							(end 0.1524 0.127)
						)
					)
					(width 0)
					(fill yes)
				)
			)
		)
		(pad "2" smd custom
			(at 0 0.2794 180)
			(size 0.0762 0.0762)
			(layers "F.Cu" "F.Mask" "F.Paste")
			(net "SAS_EXP_GF_TX_DP15")
			(options
				(clearance outline)
				(anchor circle)
			)
			(primitives
				(gr_poly
					(pts
						(arc
							(start 0.1524 -0.127)
							(mid 0.137521 -0.162921)
							(end 0.1016 -0.1778)
						)
						(arc
							(start -0.1016 -0.1778)
							(mid -0.137521 -0.162921)
							(end -0.1524 -0.127)
						)
						(arc
							(start -0.1524 0.127)
							(mid -0.137521 0.162921)
							(end -0.1016 0.1778)
						)
						(arc
							(start 0.1016 0.1778)
							(mid 0.137521 0.162921)
							(end 0.1524 0.127)
						)
					)
					(width 0)
					(fill yes)
				)
			)
		)
	)
	(footprint ""
		(layer "F.Cu")
		(at 260.277864 -218.558872 180)
		(property "Reference" "PC93"
			(at 0 0 180)
			(layer "F.SilkS")
			(hide yes)
			(effects
				(font
					(size 1.27 1.27)
				)
			)
		)
		(property "Value" "SC1KP50V2KX-1GP"
			(at 1.1811 -2.7051 180)
			(unlocked yes)
			(layer "F.Fab")
			(hide yes)
			(effects
				(font
					(size 1.016 1.016)
					(thickness 0.1524)
				)
			)
		)
		(property "Device Type" "C402H22"
			(at 1.1811 -4.2291 180)
			(unlocked yes)
			(layer "F.Fab")
			(hide yes)
			(effects
				(font
					(size 1.016 1.016)
					(thickness 0.1524)
				)
			)
		)
		(duplicate_pad_numbers_are_jumpers no)
		(fp_rect
			(start -0.4318 0.9525)
			(end 0.4318 -0.9525)
			(stroke
				(width 0)
				(type default)
			)
			(fill no)
			(layer "F.CrtYd")
		)
		(fp_rect
			(start -0.4318 0.9525)
			(end 0.4318 -0.9525)
			(stroke
				(width 0)
				(type default)
			)
			(fill no)
			(layer "F.Fab")
		)
		(pad "1" smd custom
			(at 0 -0.4445 180)
			(size 0.1524 0.1524)
			(layers "F.Cu" "F.Mask" "F.Paste")
			(net "TPS74801_1V26_STBY_OUT")
			(options
				(clearance outline)
				(anchor circle)
			)
			(primitives
				(gr_poly
					(pts
						(arc
							(start 0.3048 -0.2032)
							(mid 0.275042 -0.275042)
							(end 0.2032 -0.3048)
						)
						(arc
							(start -0.2032 -0.3048)
							(mid -0.275042 -0.275042)
							(end -0.3048 -0.2032)
						)
						(arc
							(start -0.3048 0.2032)
							(mid -0.275042 0.275042)
							(end -0.2032 0.3048)
						)
						(arc
							(start 0.2032 0.3048)
							(mid 0.275042 0.275042)
							(end 0.3048 0.2032)
						)
					)
					(width 0)
					(fill yes)
				)
			)
		)
		(pad "2" smd custom
			(at 0 0.4445 180)
			(size 0.1524 0.1524)
			(layers "F.Cu" "F.Mask" "F.Paste")
			(net "TPS74801_1V26_STBY_FB")
			(options
				(clearance outline)
				(anchor circle)
			)
			(primitives
				(gr_poly
					(pts
						(arc
							(start 0.3048 -0.2032)
							(mid 0.275042 -0.275042)
							(end 0.2032 -0.3048)
						)
						(arc
							(start -0.2032 -0.3048)
							(mid -0.275042 -0.275042)
							(end -0.3048 -0.2032)
						)
						(arc
							(start -0.3048 0.2032)
							(mid -0.275042 0.275042)
							(end -0.2032 0.3048)
						)
						(arc
							(start 0.2032 0.3048)
							(mid 0.275042 0.275042)
							(end 0.3048 0.2032)
						)
					)
					(width 0)
					(fill yes)
				)
			)
		)
	)
	(footprint ""
		(layer "F.Cu")
		(at 318.008 -180.721 -90)
		(property "Reference" "R337"
			(at 0 0 270)
			(layer "F.SilkS")
			(hide yes)
			(effects
				(font
					(size 1.27 1.27)
				)
			)
		)
		(property "Value" "49K9R2F-L-GP"
			(at 0.064008 -3.993896 270)
			(unlocked yes)
			(layer "F.Fab")
			(hide yes)
			(effects
				(font
					(size 1.016 1.016)
					(thickness 0.1524)
				)
			)
		)
		(property "Device Type" "R402H16"
			(at 0.064008 -5.517896 270)
			(unlocked yes)
			(layer "F.Fab")
			(hide yes)
			(effects
				(font
					(size 1.016 1.016)
					(thickness 0.1524)
				)
			)
		)
		(duplicate_pad_numbers_are_jumpers no)
		(fp_line
			(start -0.508 -0.9398)
			(end -0.508 0.9398)
			(stroke
				(width 0.1524)
				(type default)
			)
			(layer "F.SilkS")
		)
		(fp_line
			(start 0.508 -0.9398)
			(end -0.508 -0.9398)
			(stroke
				(width 0.1524)
				(type default)
			)
			(layer "F.SilkS")
		)
		(fp_rect
			(start -0.508 0.9398)
			(end 0.508 -0.9398)
			(stroke
				(width 0)
				(type default)
			)
			(fill no)
			(layer "F.CrtYd")
		)
		(fp_rect
			(start -0.508 0.9398)
			(end 0.508 -0.9398)
			(stroke
				(width 0)
				(type default)
			)
			(fill no)
			(layer "F.Fab")
		)
		(pad "1" smd custom
			(at 0 -0.4445 270)
			(size 0.1397 0.1397)
			(layers "F.Cu" "F.Mask" "F.Paste")
			(net "GND")
			(options
				(clearance outline)
				(anchor circle)
			)
			(primitives
				(gr_poly
					(pts
						(arc
							(start -0.1778 -0.2794)
							(mid -0.249642 -0.249642)
							(end -0.2794 -0.1778)
						)
						(arc
							(start -0.2794 0.1778)
							(mid -0.249642 0.249642)
							(end -0.1778 0.2794)
						)
						(arc
							(start 0.1778 0.2794)
							(mid 0.249642 0.249642)
							(end 0.2794 0.1778)
						)
						(arc
							(start 0.2794 -0.1778)
							(mid 0.249642 -0.249642)
							(end 0.1778 -0.2794)
						)
					)
					(width 0)
					(fill yes)
				)
			)
		)
		(pad "2" smd custom
			(at 0 0.4445 270)
			(size 0.1397 0.1397)
			(layers "F.Cu" "F.Mask" "F.Paste")
			(net "ADCVREXT")
			(options
				(clearance outline)
				(anchor circle)
			)
			(primitives
				(gr_poly
					(pts
						(arc
							(start -0.1778 -0.2794)
							(mid -0.249642 -0.249642)
							(end -0.2794 -0.1778)
						)
						(arc
							(start -0.2794 0.1778)
							(mid -0.249642 0.249642)
							(end -0.1778 0.2794)
						)
						(arc
							(start 0.1778 0.2794)
							(mid 0.249642 0.249642)
							(end 0.2794 0.1778)
						)
						(arc
							(start 0.2794 -0.1778)
							(mid 0.249642 -0.249642)
							(end 0.1778 -0.2794)
						)
					)
					(width 0)
					(fill yes)
				)
			)
		)
	)
	(footprint ""
		(layer "F.Cu")
		(at 84.34197 -134.366)
		(property "Reference" "SU72"
			(at 0 0 0)
			(layer "F.SilkS")
			(hide yes)
			(effects
				(font
					(size 1.27 1.27)
				)
			)
		)
		(property "Value" "SNLVC8T245DGVR-GP"
			(at 0 -11.1252 0)
			(unlocked yes)
			(layer "F.Fab")
			(hide yes)
			(effects
				(font
					(size 1.016 1.016)
					(thickness 0.1524)
				)
			)
		)
		(property "Device Type" "TVSOP24H48"
			(at 0 -12.6492 0)
			(unlocked yes)
			(layer "F.Fab")
			(hide yes)
			(effects
				(font
					(size 1.016 1.016)
					(thickness 0.1524)
				)
			)
		)
		(duplicate_pad_numbers_are_jumpers no)
		(fp_line
			(start -2.9337 -1.397)
			(end -2.9337 1.397)
			(stroke
				(width 0.1524)
				(type default)
			)
			(layer "F.SilkS")
		)
		(fp_line
			(start -2.9337 -0.3683)
			(end -2.5654 0)
			(stroke
				(width 0.1524)
				(type default)
			)
			(layer "F.SilkS")
		)
		(fp_line
			(start -2.9337 1.397)
			(end 2.2987 1.397)
			(stroke
				(width 0.1524)
				(type default)
			)
			(layer "F.SilkS")
		)
		(fp_line
			(start -2.7559 1.397)
			(end -2.7559 3.8354)
			(stroke
				(width 0.508)
				(type default)
			)
			(layer "F.SilkS")
		)
		(fp_line
			(start -2.5654 0)
			(end -2.9337 0.3683)
			(stroke
				(width 0.1524)
				(type default)
			)
			(layer "F.SilkS")
		)
		(fp_line
			(start 2.2987 -1.397)
			(end -2.9337 -1.397)
			(stroke
				(width 0.1524)
				(type default)
			)
			(layer "F.SilkS")
		)
		(fp_line
			(start 2.2987 1.397)
			(end 2.2987 -1.397)
			(stroke
				(width 0.1524)
				(type default)
			)
			(layer "F.SilkS")
		)
		(fp_rect
			(start -3.0099 4.0894)
			(end 3.0099 -4.0894)
			(stroke
				(width 0)
				(type default)
			)
			(fill no)
			(layer "F.CrtYd")
		)
		(fp_poly
			(pts
				(xy -3.0099 -4.0894) (xy 3.0099 -4.0894) (xy 3.0099 4.0894) (xy -3.0099 4.0894)
			)
			(stroke
				(width 0)
				(type default)
			)
			(fill no)
			(layer "F.Fab")
		)
		(pad "1" smd rect
			(at -2.19964 2.8194)
			(size 0.2032 1.524)
			(layers "F.Cu" "F.Mask" "F.Paste")
			(net "P1V8_E")
		)
		(pad "2" smd rect
			(at -1.79959 2.8194)
			(size 0.2032 1.524)
			(layers "F.Cu" "F.Mask" "F.Paste")
			(net "P1V8_E")
		)
		(pad "3" smd rect
			(at -1.39954 2.8194)
			(size 0.2032 1.524)
			(layers "F.Cu" "F.Mask" "F.Paste")
			(net "EXP_GPIO_3")
		)
		(pad "4" smd rect
			(at -0.99949 2.8194)
			(size 0.2032 1.524)
			(layers "F.Cu" "F.Mask" "F.Paste")
			(net "EXP_GPIO_7")
		)
		(pad "5" smd rect
			(at -0.59944 2.8194)
			(size 0.2032 1.524)
			(layers "F.Cu" "F.Mask" "F.Paste")
			(net "EXP_GPIO_9")
		)
		(pad "6" smd rect
			(at -0.19939 2.8194)
			(size 0.2032 1.524)
			(layers "F.Cu" "F.Mask" "F.Paste")
			(net "EXP_GPIO_10")
		)
		(pad "7" smd rect
			(at 0.19939 2.8194)
			(size 0.2032 1.524)
			(layers "F.Cu" "F.Mask" "F.Paste")
			(net "EXP_GPIO_11")
		)
		(pad "8" smd rect
			(at 0.59944 2.8194)
			(size 0.2032 1.524)
			(layers "F.Cu" "F.Mask" "F.Paste")
			(net "Net_1015")
		)
		(pad "9" smd rect
			(at 0.99949 2.8194)
			(size 0.2032 1.524)
			(layers "F.Cu" "F.Mask" "F.Paste")
			(net "Net_1016")
		)
		(pad "10" smd rect
			(at 1.39954 2.8194)
			(size 0.2032 1.524)
			(layers "F.Cu" "F.Mask" "F.Paste")
			(net "Net_1017")
		)
		(pad "11" smd rect
			(at 1.79959 2.8194)
			(size 0.2032 1.524)
			(layers "F.Cu" "F.Mask" "F.Paste")
			(net "GND")
		)
		(pad "12" smd rect
			(at 2.19964 2.8194)
			(size 0.2032 1.524)
			(layers "F.Cu" "F.Mask" "F.Paste")
			(net "GND")
		)
		(pad "13" smd rect
			(at 2.19964 -2.8194)
			(size 0.2032 1.524)
			(layers "F.Cu" "F.Mask" "F.Paste")
			(net "GND")
		)
		(pad "14" smd rect
			(at 1.79959 -2.8194)
			(size 0.2032 1.524)
			(layers "F.Cu" "F.Mask" "F.Paste")
			(net "Net_1012")
		)
		(pad "15" smd rect
			(at 1.39954 -2.8194)
			(size 0.2032 1.524)
			(layers "F.Cu" "F.Mask" "F.Paste")
			(net "Net_1013")
		)
		(pad "16" smd rect
			(at 0.99949 -2.8194)
			(size 0.2032 1.524)
			(layers "F.Cu" "F.Mask" "F.Paste")
			(net "Net_1014")
		)
		(pad "17" smd rect
			(at 0.59944 -2.8194)
			(size 0.2032 1.524)
			(layers "F.Cu" "F.Mask" "F.Paste")
			(net "BUS_SW_EN")
		)
		(pad "18" smd rect
			(at 0.19939 -2.8194)
			(size 0.2032 1.524)
			(layers "F.Cu" "F.Mask" "F.Paste")
			(net "HDD_LED_RESET_N")
		)
		(pad "19" smd rect
			(at -0.19939 -2.8194)
			(size 0.2032 1.524)
			(layers "F.Cu" "F.Mask" "F.Paste")
			(net "HDD_PWR_RESET_N")
		)
		(pad "20" smd rect
			(at -0.59944 -2.8194)
			(size 0.2032 1.524)
			(layers "F.Cu" "F.Mask" "F.Paste")
			(net "EXP_HB")
		)
		(pad "21" smd rect
			(at -0.99949 -2.8194)
			(size 0.2032 1.524)
			(layers "F.Cu" "F.Mask" "F.Paste")
			(net "FAN_PWM_PCIE_R")
		)
		(pad "22" smd rect
			(at -1.39954 -2.8194)
			(size 0.2032 1.524)
			(layers "F.Cu" "F.Mask" "F.Paste")
			(net "GND")
		)
		(pad "23" smd rect
			(at -1.79959 -2.8194)
			(size 0.2032 1.524)
			(layers "F.Cu" "F.Mask" "F.Paste")
			(net "P3V3_STBY")
		)
		(pad "24" smd rect
			(at -2.19964 -2.8194)
			(size 0.2032 1.524)
			(layers "F.Cu" "F.Mask" "F.Paste")
			(net "P3V3_STBY")
		)
	)
	(footprint ""
		(layer "F.Cu")
		(at 271.901412 -190.937896)
		(property "Reference" "R299"
			(at 0 0 0)
			(layer "F.SilkS")
			(hide yes)
			(effects
				(font
					(size 1.27 1.27)
				)
			)
		)
		(property "Value" "0R2J-2-GP"
			(at 0.064008 -3.993896 0)
			(unlocked yes)
			(layer "F.Fab")
			(hide yes)
			(effects
				(font
					(size 1.016 1.016)
					(thickness 0.1524)
				)
			)
		)
		(property "Device Type" "R402H16"
			(at 0.064008 -5.517896 0)
			(unlocked yes)
			(layer "F.Fab")
			(hide yes)
			(effects
				(font
					(size 1.016 1.016)
					(thickness 0.1524)
				)
			)
		)
		(duplicate_pad_numbers_are_jumpers no)
		(fp_line
			(start -0.508 -0.9398)
			(end -0.508 0.9398)
			(stroke
				(width 0.1524)
				(type default)
			)
			(layer "F.SilkS")
		)
		(fp_line
			(start 0.508 -0.9398)
			(end -0.508 -0.9398)
			(stroke
				(width 0.1524)
				(type default)
			)
			(layer "F.SilkS")
		)
		(fp_rect
			(start -0.508 0.9398)
			(end 0.508 -0.9398)
			(stroke
				(width 0)
				(type default)
			)
			(fill no)
			(layer "F.CrtYd")
		)
		(fp_rect
			(start -0.508 0.9398)
			(end 0.508 -0.9398)
			(stroke
				(width 0)
				(type default)
			)
			(fill no)
			(layer "F.Fab")
		)
		(pad "1" smd custom
			(at 0 -0.4445)
			(size 0.1397 0.1397)
			(layers "F.Cu" "F.Mask" "F.Paste")
			(net "FM_BMC_RESET_N")
			(options
				(clearance outline)
				(anchor circle)
			)
			(primitives
				(gr_poly
					(pts
						(arc
							(start -0.1778 -0.2794)
							(mid -0.249642 -0.249642)
							(end -0.2794 -0.1778)
						)
						(arc
							(start -0.2794 0.1778)
							(mid -0.249642 0.249642)
							(end -0.1778 0.2794)
						)
						(arc
							(start 0.1778 0.2794)
							(mid 0.249642 0.249642)
							(end 0.2794 0.1778)
						)
						(arc
							(start 0.2794 -0.1778)
							(mid 0.249642 -0.249642)
							(end 0.1778 -0.2794)
						)
					)
					(width 0)
					(fill yes)
				)
			)
		)
		(pad "2" smd custom
			(at 0 0.4445)
			(size 0.1397 0.1397)
			(layers "F.Cu" "F.Mask" "F.Paste")
			(net "BMC0_SRST_N")
			(options
				(clearance outline)
				(anchor circle)
			)
			(primitives
				(gr_poly
					(pts
						(arc
							(start -0.1778 -0.2794)
							(mid -0.249642 -0.249642)
							(end -0.2794 -0.1778)
						)
						(arc
							(start -0.2794 0.1778)
							(mid -0.249642 0.249642)
							(end -0.1778 0.2794)
						)
						(arc
							(start 0.1778 0.2794)
							(mid 0.249642 0.249642)
							(end 0.2794 0.1778)
						)
						(arc
							(start 0.2794 -0.1778)
							(mid 0.249642 -0.249642)
							(end 0.1778 -0.2794)
						)
					)
					(width 0)
					(fill yes)
				)
			)
		)
	)
	(footprint ""
		(layer "F.Cu")
		(at 80.626966 -91.567 -90)
		(property "Reference" "SL22"
			(at 0 0 270)
			(layer "F.SilkS")
			(hide yes)
			(effects
				(font
					(size 1.27 1.27)
				)
			)
		)
		(property "Value" "MPZ2012S601AT-GP"
			(at 0 -4.2418 270)
			(unlocked yes)
			(layer "F.Fab")
			(hide yes)
			(effects
				(font
					(size 1.016 1.016)
					(thickness 0.1524)
				)
			)
		)
		(property "Device Type" "L805H42"
			(at 0 -5.7912 270)
			(unlocked yes)
			(layer "F.Fab")
			(hide yes)
			(effects
				(font
					(size 1.016 1.016)
					(thickness 0.1524)
				)
			)
		)
		(duplicate_pad_numbers_are_jumpers no)
		(fp_line
			(start -0.889 1.7018)
			(end -0.889 -1.7018)
			(stroke
				(width 0.1524)
				(type default)
			)
			(layer "F.SilkS")
		)
		(fp_line
			(start 0.889 1.7018)
			(end -0.889 1.7018)
			(stroke
				(width 0.1524)
				(type default)
			)
			(layer "F.SilkS")
		)
		(fp_line
			(start -0.889 -1.7018)
			(end 0.889 -1.7018)
			(stroke
				(width 0.1524)
				(type default)
			)
			(layer "F.SilkS")
		)
		(fp_line
			(start 0.889 -1.7018)
			(end 0.889 1.7018)
			(stroke
				(width 0.1524)
				(type default)
			)
			(layer "F.SilkS")
		)
		(fp_rect
			(start -0.9652 1.778)
			(end 0.9652 -1.778)
			(stroke
				(width 0)
				(type default)
			)
			(fill no)
			(layer "F.CrtYd")
		)
		(fp_rect
			(start -0.9652 1.778)
			(end 0.9652 -1.778)
			(stroke
				(width 0)
				(type default)
			)
			(fill no)
			(layer "F.Fab")
		)
		(pad "1" smd rect
			(at 0 -0.9652 270)
			(size 1.397 1.143)
			(layers "F.Cu" "F.Mask" "F.Paste")
			(net "SYSPLL_VDDA09")
		)
		(pad "2" smd rect
			(at 0 0.9652 270)
			(size 1.397 1.143)
			(layers "F.Cu" "F.Mask" "F.Paste")
			(net "P0V9_E")
		)
	)
)
